# BASEBOARD_FAB2 (Tioga Pass) — schematic netlist excerpt (pin names and nets, part order shuffled) for the footprints in the layout excerpt that follows; sources: Cadence DE-HDL packaged netlist, KiCad conversion of Wiwynn_Tioga_Pass_MB.brd

J1F1  DM-FCI-CONN76-8R-GP-U-01  pkg CONN-G4  page 181
  PCIE_RX_DP0  = P3E_CPU1_PE3_MP_RXN<0>
  GND1  = GND
  PCIE_RX_DP6  = P3E_CPU1_PE3_MP_RXP<6>
  FAN_TACH3  = FAN_TACH3_R
  MNG_TX_DP  = NIC_MDI_MNG_TX_DP
  \pmbus_alert#\  = IRQ_SML1_PMBUS_ALERT_R_N
  PCIE_TX_DP3  = P3E_CPU1_PE3_MP_C_TXN<3>
  GND2  = GND
  PCIE_RX_DN0  = P3E_CPU1_PE3_MP_RXP<0>
  PCIE_RX_DP3  = P3E_CPU1_PE3_MP_RXN<3>
  PCIE_RX_DN6  = P3E_CPU1_PE3_MP_RXN<6>
  FAN_TACH2  = FAN_TACH2_R
  MNG_TX_DN  = NIC_MDI_MNG_TX_DN
  PMBUS_DATA  = SMB_BMC_PMBUS_STBY_LVC3_SDA
  PCIE_TX_DN3  = P3E_CPU1_PE3_MP_C_TXP<3>
  PCIE_TX_DP0  = P3E_CPU1_PE3_MP_C_TXN<0>
  GND3  = GND
  PCIE_RX_DN3  = P3E_CPU1_PE3_MP_RXP<3>
  GND4  = GND
  FAN_TACH1  = FAN_TACH1_R
  GND5  = GND
  PMBUS_CLK  = SMB_BMC_PMBUS_STBY_LVC3_SCL
  GND6  = GND
  PCIE_TX_DN0  = P3E_CPU1_PE3_MP_C_TXP<0>
  PCIE_RX_DP1  = P3E_CPU1_PE3_MP_RXN<1>
  GND7  = GND
  PCIE_RX_DP7  = P3E_CPU1_PE3_MP_RXN<7>
  FAN_TACH0  = FAN_TACH0_R
  MNG_RX_DP  = NIC_MDI_MNG_RX_DP
  GND8  = GND
  PCIE_TX_DP4  = P3E_CPU1_PE3_MP_C_TXN<4>
  GND9  = GND
  PCIE_RX_DN1  = P3E_CPU1_PE3_MP_RXP<1>
  PCIE_RX_DP4  = P3E_CPU1_PE3_MP_RXN<4>
  PCIE_RX_DN7  = P3E_CPU1_PE3_MP_RXP<7>
  \mated_in#\  = FM_MATED_IN_N
  MNG_RX_DN  = NIC_MDI_MNG_RX_DN
  PCIE_TX_DP6  = P3E_CPU1_PE3_MP_C_TXN<6>
  PCIE_TX_DN4  = P3E_CPU1_PE3_MP_C_TXP<4>
  PCIE_TX_DP1  = P3E_CPU1_PE3_MP_C_TXN<1>
  GND10  = GND
  PCIE_RX_DN4  = P3E_CPU1_PE3_MP_RXP<4>
  GND11  = GND
  FAN_PWM0  = FAN_PWM_OUT_SYS0_R1
  MB_SLOT_ID0  = FM_MB_SLOT_ID0
  PCIE_TX_DN6  = P3E_CPU1_PE3_MP_C_TXP<6>
  GND12  = GND
  PCIE_TX_DN1  = P3E_CPU1_PE3_MP_C_TXP<1>
  PCIE_RX_DP2  = P3E_CPU1_PE3_MP_RXP<2>
  GND13  = GND
  COM_TX  = SPA_MID_DBG_TX_R
  GND14  = GND
  MB_SLOT_ID1  = FM_MB_SLOT_ID1
  GND15  = GND
  PCIE_TX_DP5  = P3E_CPU1_PE3_MP_C_TXP<5>
  GND16  = GND
  PCIE_RX_DN2  = P3E_CPU1_PE3_MP_RXN<2>
  PCIE_RX_DP5  = P3E_CPU1_PE3_MP_RXP<5>
  COM_RX  = SPA_MID_DBG_RX_R
  PCIE_CLK_100M_DP  = CLK_100M_AIRMAX8_PE1_DP
  MB_SLOT_ID2  = FM_MB_SLOT_ID2
  PCIE_TX_DP7  = P3E_CPU1_PE3_MP_C_TXP<7>
  PCIE_TX_DN5  = P3E_CPU1_PE3_MP_C_TXN<5>
  PCIE_TX_DP2  = P3E_CPU1_PE3_MP_C_TXN<2>
  GND17  = GND
  PCIE_RX_DN5  = P3E_CPU1_PE3_MP_RXN<5>
  \mb_on#\  = FM_ENABLE_FAN_POWER
  PCIE_CLK_100M_DN  = CLK_100M_AIRMAX8_PE1_DN
  \pcie_perst#\  = RST_PCIE_MIDPLANE_N
  PCIE_TX_DN7  = P3E_CPU1_PE3_MP_C_TXN<7>
  GND18  = GND
  PCIE_TX_DN2  = P3E_CPU1_PE3_MP_C_TXP<2>
  J2  = GND
  J4  = GND
  J6  = GND
  J8  = GND

(kicad_pcb
	(version 20260206)
	(generator "pcbnew")
	(generator_version "10.0")
	(general
		(thickness 1.6)
		(legacy_teardrops no)
	)
	(paper "A4")
	(title_block
		(title "Wiwynn_Tioga_Pass_MB.brd")
		(comment 1 "Tioga Pass / footprint 1465 of 4770 (J1F1), pads 1-29 of 76")
	)
	(layers
		(0 "F.Cu" signal "TOP")
		(4 "In1.Cu" signal "L2GND")
		(6 "In2.Cu" signal "L3")
		(8 "In3.Cu" signal "L4GND")
		(10 "In4.Cu" signal "L5")
		(12 "In5.Cu" signal "L6GND")
		(14 "In6.Cu" signal "L7VCC")
		(16 "In7.Cu" signal "L8VCC")
		(18 "In8.Cu" signal "L9GND")
		(20 "In9.Cu" signal "L10")
		(22 "In10.Cu" signal "L11GND")
		(24 "In11.Cu" signal "L12")
		(26 "In12.Cu" signal "L13GND")
		(2 "B.Cu" signal "BOTTOM")
		(9 "F.Adhes" user "F.Adhesive")
		(11 "B.Adhes" user "B.Adhesive")
		(13 "F.Paste" user "Package Geometry/Pastemask Top")
		(15 "B.Paste" user "Package Geometry/Pastemask Bottom")
		(5 "F.SilkS" user "Ref Des/Silkscreen Top")
		(7 "B.SilkS" user "Ref Des/Silkscreen Bottom")
		(1 "F.Mask" user "Board Geometry/Soldermask Top")
		(3 "B.Mask" user "Board Geometry/Soldermask Bottom")
		(17 "Dwgs.User" user "User.Drawings")
		(19 "Cmts.User" user "User.Comments")
		(21 "Eco1.User" user "User.Eco1")
		(23 "Eco2.User" user "User.Eco2")
		(25 "Edge.Cuts" user "Board Geometry/Outline")
		(27 "Margin" user)
		(31 "F.CrtYd" user "Package Geometry/Place Bound Top")
		(29 "B.CrtYd" user "Package Geometry/Place Bound Bottom")
		(35 "F.Fab" user "Ref Des/Assembly Top")
		(33 "B.Fab" user "Ref Des/Assembly Bottom")
	)
	(footprint ""
		(layer "F.Cu")
		(at 2.29997 -32.71012 -90)
		(property "Reference" "J1F1"
			(at 0 0 270)
			(layer "F.SilkS")
			(hide yes)
			(effects
				(font
					(size 1.27 1.27)
				)
			)
		)
		(property "Value" "*"
			(at -20.8026 -3.4036 270)
			(unlocked yes)
			(layer "F.Fab")
			(hide yes)
			(effects
				(font
					(size 1.27 1.016)
					(thickness 0.1524)
				)
			)
		)
		(property "Device Type" "DM-FCI-CONN76-8R-GP-U-01_CONN-A"
			(at -20.8026 -4.9276 270)
			(unlocked yes)
			(layer "F.Fab")
			(hide yes)
			(effects
				(font
					(size 1.27 1.016)
					(thickness 0.1524)
				)
			)
		)
		(duplicate_pad_numbers_are_jumpers no)
		(pad "A1" thru_hole circle
			(at -6.999986 6.199886 270)
			(size 0.8128 0.8128)
			(drill 0.399796)
			(layers "*.Cu" "*.Mask")
			(remove_unused_layers no)
			(net "P3E_CPU1_PE3_MP_RXN<0>")
			(clearance 0.2921)
			(thermal_gap 0.2921)
		)
		(pad "A2" thru_hole circle
			(at -4.99999 6.299962 270)
			(size 0.8636 0.8636)
			(drill 0.499872)
			(layers "*.Cu" "*.Mask")
			(remove_unused_layers no)
			(net "GND")
			(clearance 0.1778)
			(thermal_gap 0.1778)
		)
		(pad "A3" thru_hole circle
			(at -2.999994 6.199886 270)
			(size 0.8128 0.8128)
			(drill 0.399796)
			(layers "*.Cu" "*.Mask")
			(remove_unused_layers no)
			(net "P3E_CPU1_PE3_MP_RXP<6>")
			(clearance 0.2921)
			(thermal_gap 0.2921)
		)
		(pad "A4" thru_hole circle
			(at -0.999998 6.299962 270)
			(size 0.8636 0.8636)
			(drill 0.499872)
			(layers "*.Cu" "*.Mask")
			(remove_unused_layers no)
			(net "FAN_TACH3_R")
			(clearance 0.1778)
			(thermal_gap 0.1778)
		)
		(pad "A5" thru_hole circle
			(at 0.999998 6.199886 270)
			(size 0.8128 0.8128)
			(drill 0.399796)
			(layers "*.Cu" "*.Mask")
			(remove_unused_layers no)
			(net "NIC_MDI_MNG_TX_DP")
			(clearance 0.2921)
			(thermal_gap 0.2921)
		)
		(pad "A6" thru_hole circle
			(at 2.999994 6.299962 270)
			(size 0.8636 0.8636)
			(drill 0.499872)
			(layers "*.Cu" "*.Mask")
			(remove_unused_layers no)
			(net "IRQ_SML1_PMBUS_ALERT_R_N")
			(clearance 0.1778)
			(thermal_gap 0.1778)
		)
		(pad "A7" thru_hole circle
			(at 4.99999 6.199886 270)
			(size 0.8128 0.8128)
			(drill 0.399796)
			(layers "*.Cu" "*.Mask")
			(remove_unused_layers no)
			(net "P3E_CPU1_PE3_MP_C_TXN<3>")
			(clearance 0.2921)
			(thermal_gap 0.2921)
		)
		(pad "A8" thru_hole circle
			(at 6.999986 6.299962 270)
			(size 0.8636 0.8636)
			(drill 0.499872)
			(layers "*.Cu" "*.Mask")
			(remove_unused_layers no)
			(net "GND")
			(clearance 0.1778)
			(thermal_gap 0.1778)
		)
		(pad "B1" thru_hole circle
			(at -6.999986 4.800092 270)
			(size 0.8128 0.8128)
			(drill 0.399796)
			(layers "*.Cu" "*.Mask")
			(remove_unused_layers no)
			(net "P3E_CPU1_PE3_MP_RXP<0>")
			(clearance 0.2921)
			(thermal_gap 0.2921)
		)
		(pad "B2" thru_hole circle
			(at -4.99999 4.899914 270)
			(size 0.8128 0.8128)
			(drill 0.399796)
			(layers "*.Cu" "*.Mask")
			(remove_unused_layers no)
			(net "P3E_CPU1_PE3_MP_RXN<3>")
			(clearance 0.2921)
			(thermal_gap 0.2921)
		)
		(pad "B3" thru_hole circle
			(at -2.999994 4.800092 270)
			(size 0.8128 0.8128)
			(drill 0.399796)
			(layers "*.Cu" "*.Mask")
			(remove_unused_layers no)
			(net "P3E_CPU1_PE3_MP_RXN<6>")
			(clearance 0.2921)
			(thermal_gap 0.2921)
		)
		(pad "B4" thru_hole circle
			(at -0.999998 4.899914 270)
			(size 0.8128 0.8128)
			(drill 0.399796)
			(layers "*.Cu" "*.Mask")
			(remove_unused_layers no)
			(net "FAN_TACH2_R")
			(clearance 0.1524)
			(thermal_gap 0.1524)
		)
		(pad "B5" thru_hole circle
			(at 0.999998 4.800092 270)
			(size 0.8128 0.8128)
			(drill 0.399796)
			(layers "*.Cu" "*.Mask")
			(remove_unused_layers no)
			(net "NIC_MDI_MNG_TX_DN")
			(clearance 0.2921)
			(thermal_gap 0.2921)
		)
		(pad "B6" thru_hole circle
			(at 2.999994 4.899914 270)
			(size 0.8128 0.8128)
			(drill 0.399796)
			(layers "*.Cu" "*.Mask")
			(remove_unused_layers no)
			(net "SMB_BMC_PMBUS_STBY_LVC3_SDA")
			(clearance 0.1524)
			(thermal_gap 0.1524)
		)
		(pad "B7" thru_hole circle
			(at 4.99999 4.800092 270)
			(size 0.8128 0.8128)
			(drill 0.399796)
			(layers "*.Cu" "*.Mask")
			(remove_unused_layers no)
			(net "P3E_CPU1_PE3_MP_C_TXP<3>")
			(clearance 0.2921)
			(thermal_gap 0.2921)
		)
		(pad "B8" thru_hole circle
			(at 6.999986 4.899914 270)
			(size 0.8128 0.8128)
			(drill 0.399796)
			(layers "*.Cu" "*.Mask")
			(remove_unused_layers no)
			(net "P3E_CPU1_PE3_MP_C_TXN<0>")
			(clearance 0.2921)
			(thermal_gap 0.2921)
		)
		(pad "C1" thru_hole circle
			(at -6.999986 3.400044 270)
			(size 0.8636 0.8636)
			(drill 0.499872)
			(layers "*.Cu" "*.Mask")
			(remove_unused_layers no)
			(net "GND")
			(clearance 0.1778)
			(thermal_gap 0.1778)
		)
		(pad "C2" thru_hole circle
			(at -4.99999 3.50012 270)
			(size 0.8128 0.8128)
			(drill 0.399796)
			(layers "*.Cu" "*.Mask")
			(remove_unused_layers no)
			(net "P3E_CPU1_PE3_MP_RXP<3>")
			(clearance 0.2921)
			(thermal_gap 0.2921)
		)
		(pad "C3" thru_hole circle
			(at -2.999994 3.400044 270)
			(size 0.8636 0.8636)
			(drill 0.499872)
			(layers "*.Cu" "*.Mask")
			(remove_unused_layers no)
			(net "GND")
			(clearance 0.1778)
			(thermal_gap 0.1778)
		)
		(pad "C4" thru_hole circle
			(at -0.999998 3.50012 270)
			(size 0.8128 0.8128)
			(drill 0.399796)
			(layers "*.Cu" "*.Mask")
			(remove_unused_layers no)
			(net "FAN_TACH1_R")
			(clearance 0.1524)
			(thermal_gap 0.1524)
		)
		(pad "C5" thru_hole circle
			(at 0.999998 3.400044 270)
			(size 0.8636 0.8636)
			(drill 0.499872)
			(layers "*.Cu" "*.Mask")
			(remove_unused_layers no)
			(net "GND")
			(clearance 0.1778)
			(thermal_gap 0.1778)
		)
		(pad "C6" thru_hole circle
			(at 2.999994 3.50012 270)
			(size 0.8128 0.8128)
			(drill 0.399796)
			(layers "*.Cu" "*.Mask")
			(remove_unused_layers no)
			(net "SMB_BMC_PMBUS_STBY_LVC3_SCL")
			(clearance 0.1524)
			(thermal_gap 0.1524)
		)
		(pad "C7" thru_hole circle
			(at 4.99999 3.400044 270)
			(size 0.8636 0.8636)
			(drill 0.499872)
			(layers "*.Cu" "*.Mask")
			(remove_unused_layers no)
			(net "GND")
			(clearance 0.1778)
			(thermal_gap 0.1778)
		)
		(pad "C8" thru_hole circle
			(at 6.999986 3.50012 270)
			(size 0.8128 0.8128)
			(drill 0.399796)
			(layers "*.Cu" "*.Mask")
			(remove_unused_layers no)
			(net "P3E_CPU1_PE3_MP_C_TXP<0>")
			(clearance 0.2921)
			(thermal_gap 0.2921)
		)
		(pad "D1" thru_hole circle
			(at -6.999986 1.999996 270)
			(size 0.8128 0.8128)
			(drill 0.399796)
			(layers "*.Cu" "*.Mask")
			(remove_unused_layers no)
			(net "P3E_CPU1_PE3_MP_RXN<1>")
			(clearance 0.2921)
			(thermal_gap 0.2921)
		)
		(pad "D2" thru_hole circle
			(at -4.99999 2.100072 270)
			(size 0.8636 0.8636)
			(drill 0.499872)
			(layers "*.Cu" "*.Mask")
			(remove_unused_layers no)
			(net "GND")
			(clearance 0.1778)
			(thermal_gap 0.1778)
		)
		(pad "D3" thru_hole circle
			(at -2.999994 1.999996 270)
			(size 0.8128 0.8128)
			(drill 0.399796)
			(layers "*.Cu" "*.Mask")
			(remove_unused_layers no)
			(net "P3E_CPU1_PE3_MP_RXN<7>")
			(clearance 0.2921)
			(thermal_gap 0.2921)
		)
		(pad "D4" thru_hole circle
			(at -0.999998 2.100072 270)
			(size 0.8636 0.8636)
			(drill 0.499872)
			(layers "*.Cu" "*.Mask")
			(remove_unused_layers no)
			(net "FAN_TACH0_R")
			(clearance 0.1778)
			(thermal_gap 0.1778)
		)
		(pad "D5" thru_hole circle
			(at 0.999998 1.999996 270)
			(size 0.8128 0.8128)
			(drill 0.399796)
			(layers "*.Cu" "*.Mask")
			(remove_unused_layers no)
			(net "NIC_MDI_MNG_RX_DP")
			(clearance 0.2921)
			(thermal_gap 0.2921)
		)
	)
)
